# BASEBOARD_FAB2 (Tioga Pass) — schematic netlist excerpt (pin names and nets, part order shuffled) for the footprints in the layout excerpt that follows; sources: Cadence DE-HDL packaged netlist, KiCad conversion of Wiwynn_Tioga_Pass_MB.brd

R7E19  RES  1.00K 1% EMPTY  pkg 0402  page 192 : A = P3V3_STBY ; B = FM_MEM_EVENT_FUNC
R6N4  RES  51.1 1.0% CHIP  pkg 0402  page 205 : A = PVSA_CPU0 ; B = GND
R3R8  RES  20.0 1% CHIP  pkg 0402  page 99 : A = SMB_DDR_DEF_VPP_SCL_R ; B = SMB_DDR_DEF_VPP_SCL

(kicad_pcb
	(version 20260206)
	(generator "pcbnew")
	(generator_version "10.0")
	(general
		(thickness 1.6)
		(legacy_teardrops no)
	)
	(paper "A4")
	(title_block
		(title "Wiwynn_Tioga_Pass_MB.brd")
		(comment 1 "Tioga Pass / footprints 3441-3443 of 4770")
	)
	(layers
		(0 "F.Cu" signal "TOP")
		(4 "In1.Cu" signal "L2GND")
		(6 "In2.Cu" signal "L3")
		(8 "In3.Cu" signal "L4GND")
		(10 "In4.Cu" signal "L5")
		(12 "In5.Cu" signal "L6GND")
		(14 "In6.Cu" signal "L7VCC")
		(16 "In7.Cu" signal "L8VCC")
		(18 "In8.Cu" signal "L9GND")
		(20 "In9.Cu" signal "L10")
		(22 "In10.Cu" signal "L11GND")
		(24 "In11.Cu" signal "L12")
		(26 "In12.Cu" signal "L13GND")
		(2 "B.Cu" signal "BOTTOM")
		(9 "F.Adhes" user "F.Adhesive")
		(11 "B.Adhes" user "B.Adhesive")
		(13 "F.Paste" user "Package Geometry/Pastemask Top")
		(15 "B.Paste" user "Package Geometry/Pastemask Bottom")
		(5 "F.SilkS" user "Ref Des/Silkscreen Top")
		(7 "B.SilkS" user "Ref Des/Silkscreen Bottom")
		(1 "F.Mask" user "Board Geometry/Soldermask Top")
		(3 "B.Mask" user "Board Geometry/Soldermask Bottom")
		(17 "Dwgs.User" user "User.Drawings")
		(19 "Cmts.User" user "User.Comments")
		(21 "Eco1.User" user "User.Eco1")
		(23 "Eco2.User" user "User.Eco2")
		(25 "Edge.Cuts" user "Board Geometry/Outline")
		(27 "Margin" user)
		(31 "F.CrtYd" user "Package Geometry/Place Bound Top")
		(29 "B.CrtYd" user "Package Geometry/Place Bound Bottom")
		(35 "F.Fab" user "Ref Des/Assembly Top")
		(33 "B.Fab" user "Ref Des/Assembly Bottom")
	)
	(footprint ""
		(layer "B.Cu")
		(at 214.581232 -98.1202)
		(property "Reference" "R6N4"
			(at 0 0 0)
			(layer "B.SilkS")
			(hide yes)
			(effects
				(font
					(size 1.27 1.27)
				)
				(justify mirror)
			)
		)
		(property "Value" ""
			(at 0 0 0)
			(layer "B.Fab")
			(effects
				(font
					(size 1.27 1.27)
				)
				(justify mirror)
			)
		)
		(duplicate_pad_numbers_are_jumpers no)
		(fp_poly
			(pts
				(xy 0.2794 -0.1016) (xy -0.2794 -0.1016) (xy -0.2794 0.9906) (xy 0.2794 0.9906)
			)
			(stroke
				(width 0)
				(type default)
			)
			(fill no)
			(layer "B.CrtYd")
		)
		(fp_line
			(start -0.2794 -0.1016)
			(end 0.2794 -0.1016)
			(stroke
				(width 0.1)
				(type default)
			)
			(layer "B.Fab")
		)
		(fp_line
			(start -0.2794 0.9906)
			(end -0.2794 -0.1016)
			(stroke
				(width 0.1)
				(type default)
			)
			(layer "B.Fab")
		)
		(fp_line
			(start 0.2794 -0.1016)
			(end 0.2794 0.9906)
			(stroke
				(width 0.1)
				(type default)
			)
			(layer "B.Fab")
		)
		(fp_line
			(start 0.2794 0.9906)
			(end -0.2794 0.9906)
			(stroke
				(width 0.1)
				(type default)
			)
			(layer "B.Fab")
		)
		(pad "1" smd rect
			(at 0 0 180)
			(size 0.508 0.508)
			(layers "B.Cu" "B.Mask" "B.Paste")
			(net "PVSA_CPU0")
		)
		(pad "2" smd rect
			(at 0 0.889 180)
			(size 0.508 0.508)
			(layers "B.Cu" "B.Mask" "B.Paste")
			(net "GND")
		)
		(zone
			(layer "B.Cu")
			(hatch none 0.5)
			(connect_pads
				(clearance 0)
			)
			(min_thickness 0.25)
			(keepout
				(tracks allowed)
				(vias not_allowed)
				(pads allowed)
				(copperpour not_allowed)
				(footprints allowed)
			)
			(placement
				(enabled no)
				(sheetname "")
			)
			(fill
				(thermal_gap 0.5)
				(thermal_bridge_width 0.5)
				(island_removal_mode 0)
			)
			(polygon
				(pts
					(xy 214.835232 -97.8662) (xy 214.327232 -97.8662) (xy 214.327232 -97.4852) (xy 214.835232 -97.4852)
				)
			)
		)
		(zone
			(layer "B.Cu")
			(hatch none 0.5)
			(connect_pads
				(clearance 0)
			)
			(min_thickness 0.25)
			(keepout
				(tracks not_allowed)
				(vias allowed)
				(pads allowed)
				(copperpour not_allowed)
				(footprints allowed)
			)
			(placement
				(enabled no)
				(sheetname "")
			)
			(fill
				(thermal_gap 0.5)
				(thermal_bridge_width 0.5)
				(island_removal_mode 0)
			)
			(polygon
				(pts
					(xy 214.835232 -97.4852) (xy 214.327232 -97.4852) (xy 214.327232 -97.8662) (xy 214.835232 -97.8662)
				)
			)
		)
	)
	(footprint ""
		(layer "B.Cu")
		(at 317.72606 -125.42774 180)
		(property "Reference" "R3R8"
			(at 0 0 0)
			(layer "B.SilkS")
			(hide yes)
			(effects
				(font
					(size 1.27 1.27)
				)
				(justify mirror)
			)
		)
		(property "Value" ""
			(at 0 0 0)
			(layer "B.Fab")
			(effects
				(font
					(size 1.27 1.27)
				)
				(justify mirror)
			)
		)
		(duplicate_pad_numbers_are_jumpers no)
		(fp_poly
			(pts
				(xy 0.2794 -0.1016) (xy -0.2794 -0.1016) (xy -0.2794 0.9906) (xy 0.2794 0.9906)
			)
			(stroke
				(width 0)
				(type default)
			)
			(fill no)
			(layer "B.CrtYd")
		)
		(fp_line
			(start 0.2794 0.9906)
			(end -0.2794 0.9906)
			(stroke
				(width 0.1)
				(type default)
			)
			(layer "B.Fab")
		)
		(fp_line
			(start 0.2794 -0.1016)
			(end 0.2794 0.9906)
			(stroke
				(width 0.1)
				(type default)
			)
			(layer "B.Fab")
		)
		(fp_line
			(start -0.2794 0.9906)
			(end -0.2794 -0.1016)
			(stroke
				(width 0.1)
				(type default)
			)
			(layer "B.Fab")
		)
		(fp_line
			(start -0.2794 -0.1016)
			(end 0.2794 -0.1016)
			(stroke
				(width 0.1)
				(type default)
			)
			(layer "B.Fab")
		)
		(pad "1" smd rect
			(at 0 0)
			(size 0.508 0.508)
			(layers "B.Cu" "B.Mask" "B.Paste")
			(net "SMB_DDR_DEF_VPP_SCL_R")
		)
		(pad "2" smd rect
			(at 0 0.889)
			(size 0.508 0.508)
			(layers "B.Cu" "B.Mask" "B.Paste")
			(net "SMB_DDR_DEF_VPP_SCL")
		)
		(zone
			(layer "B.Cu")
			(hatch none 0.5)
			(connect_pads
				(clearance 0)
			)
			(min_thickness 0.25)
			(keepout
				(tracks not_allowed)
				(vias allowed)
				(pads allowed)
				(copperpour not_allowed)
				(footprints allowed)
			)
			(placement
				(enabled no)
				(sheetname "")
			)
			(fill
				(thermal_gap 0.5)
				(thermal_bridge_width 0.5)
				(island_removal_mode 0)
			)
			(polygon
				(pts
					(xy 317.47206 -126.06274) (xy 317.98006 -126.06274) (xy 317.98006 -125.68174) (xy 317.47206 -125.68174)
				)
			)
		)
		(zone
			(layer "B.Cu")
			(hatch none 0.5)
			(connect_pads
				(clearance 0)
			)
			(min_thickness 0.25)
			(keepout
				(tracks allowed)
				(vias not_allowed)
				(pads allowed)
				(copperpour not_allowed)
				(footprints allowed)
			)
			(placement
				(enabled no)
				(sheetname "")
			)
			(fill
				(thermal_gap 0.5)
				(thermal_bridge_width 0.5)
				(island_removal_mode 0)
			)
			(polygon
				(pts
					(xy 317.47206 -125.68174) (xy 317.98006 -125.68174) (xy 317.98006 -126.06274) (xy 317.47206 -126.06274)
				)
			)
		)
	)
	(footprint ""
		(layer "B.Cu")
		(at 382.782826 -72.058276 -90)
		(property "Reference" "R7E19"
			(at 0 0 90)
			(layer "B.SilkS")
			(hide yes)
			(effects
				(font
					(size 1.27 1.27)
				)
				(justify mirror)
			)
		)
		(property "Value" ""
			(at 0 0 90)
			(layer "B.Fab")
			(effects
				(font
					(size 1.27 1.27)
				)
				(justify mirror)
			)
		)
		(duplicate_pad_numbers_are_jumpers no)
		(fp_poly
			(pts
				(xy 0.2794 -0.1016) (xy -0.2794 -0.1016) (xy -0.2794 0.9906) (xy 0.2794 0.9906)
			)
			(stroke
				(width 0)
				(type default)
			)
			(fill no)
			(layer "B.CrtYd")
		)
		(fp_line
			(start -0.2794 0.9906)
			(end -0.2794 -0.1016)
			(stroke
				(width 0.1)
				(type default)
			)
			(layer "B.Fab")
		)
		(fp_line
			(start 0.2794 0.9906)
			(end -0.2794 0.9906)
			(stroke
				(width 0.1)
				(type default)
			)
			(layer "B.Fab")
		)
		(fp_line
			(start -0.2794 -0.1016)
			(end 0.2794 -0.1016)
			(stroke
				(width 0.1)
				(type default)
			)
			(layer "B.Fab")
		)
		(fp_line
			(start 0.2794 -0.1016)
			(end 0.2794 0.9906)
			(stroke
				(width 0.1)
				(type default)
			)
			(layer "B.Fab")
		)
		(pad "1" smd rect
			(at 0 0 90)
			(size 0.508 0.508)
			(layers "B.Cu" "B.Mask" "B.Paste")
			(net "P3V3_STBY")
		)
		(pad "2" smd rect
			(at 0 0.889 90)
			(size 0.508 0.508)
			(layers "B.Cu" "B.Mask" "B.Paste")
			(net "FM_MEM_EVENT_FUNC")
		)
		(zone
			(layer "B.Cu")
			(hatch none 0.5)
			(connect_pads
				(clearance 0)
			)
			(min_thickness 0.25)
			(keepout
				(tracks not_allowed)
				(vias allowed)
				(pads allowed)
				(copperpour not_allowed)
				(footprints allowed)
			)
			(placement
				(enabled no)
				(sheetname "")
			)
			(fill
				(thermal_gap 0.5)
				(thermal_bridge_width 0.5)
				(island_removal_mode 0)
			)
			(polygon
				(pts
					(xy 382.147826 -71.804276) (xy 382.147826 -72.312276) (xy 382.528826 -72.312276) (xy 382.528826 -71.804276)
				)
			)
		)
		(zone
			(layer "B.Cu")
			(hatch none 0.5)
			(connect_pads
				(clearance 0)
			)
			(min_thickness 0.25)
			(keepout
				(tracks allowed)
				(vias not_allowed)
				(pads allowed)
				(copperpour not_allowed)
				(footprints allowed)
			)
			(placement
				(enabled no)
				(sheetname "")
			)
			(fill
				(thermal_gap 0.5)
				(thermal_bridge_width 0.5)
				(island_removal_mode 0)
			)
			(polygon
				(pts
					(xy 382.528826 -71.804276) (xy 382.528826 -72.312276) (xy 382.147826 -72.312276) (xy 382.147826 -71.804276)
				)
			)
		)
	)
)
